(kicad_pcb
	(version 20260206)
	(generator "pcbnew")
	(generator_version "10.0")
	(general
		(thickness 1.6)
		(legacy_teardrops no)
	)
	(paper "A4")
	(title_block
		(title "01162023_DA0F0TEBIF0_F0T_Expander_BD_F_brd_V02_OCP.brd")
		(comment 1 "Grand Teton / footprints 7394-7401 of 9728")
	)
	(layers
		(0 "F.Cu" signal "TOP")
		(4 "In1.Cu" signal "GND")
		(6 "In2.Cu" signal "VCC")
		(8 "In3.Cu" signal "VCC1")
		(10 "In4.Cu" signal "GND1")
		(12 "In5.Cu" signal "IN1")
		(14 "In6.Cu" signal "GND2")
		(16 "In7.Cu" signal "IN2")
		(18 "In8.Cu" signal "GND3")
		(20 "In9.Cu" signal "IN3")
		(22 "In10.Cu" signal "GND4")
		(24 "In11.Cu" signal "IN4")
		(26 "In12.Cu" signal "GND5")
		(28 "In13.Cu" signal "IN5")
		(30 "In14.Cu" signal "GND6")
		(32 "In15.Cu" signal "IN6")
		(34 "In16.Cu" signal "GND7")
		(2 "B.Cu" signal "BOTTOM")
		(9 "F.Adhes" user "F.Adhesive")
		(11 "B.Adhes" user "B.Adhesive")
		(13 "F.Paste" user "Package Geometry/Pastemask Top")
		(15 "B.Paste" user "Package Geometry/Pastemask Bottom")
		(5 "F.SilkS" user "Ref Des/Silkscreen Top")
		(7 "B.SilkS" user "Ref Des/Silkscreen Bottom")
		(1 "F.Mask" user "Board Geometry/Soldermask Top")
		(3 "B.Mask" user "Board Geometry/Soldermask Bottom")
		(17 "Dwgs.User" user "User.Drawings")
		(19 "Cmts.User" user "User.Comments")
		(21 "Eco1.User" user "User.Eco1")
		(23 "Eco2.User" user "User.Eco2")
		(25 "Edge.Cuts" user "Board Geometry/Outline")
		(27 "Margin" user)
		(31 "F.CrtYd" user "Package Geometry/Place Bound Top")
		(29 "B.CrtYd" user "Package Geometry/Place Bound Bottom")
		(35 "F.Fab" user "Ref Des/Assembly Top")
		(33 "B.Fab" user "Ref Des/Assembly Bottom")
	)
	(footprint ""
		(layer "B.Cu")
		(at 229.222046 -141.316202)
		(property "Reference" "C2796"
			(at 0 0 0)
			(layer "B.SilkS")
			(hide yes)
			(effects
				(font
					(size 1.27 1.27)
				)
				(justify mirror)
			)
		)
		(property "Value" ""
			(at 0 0 0)
			(layer "B.Fab")
			(effects
				(font
					(size 1.27 1.27)
				)
				(justify mirror)
			)
		)
		(duplicate_pad_numbers_are_jumpers no)
		(fp_line
			(start -0.7874 -0.4064)
			(end -0.7874 0.4064)
			(stroke
				(width 0.1524)
				(type default)
			)
			(layer "B.SilkS")
		)
		(fp_line
			(start -0.7874 0.4064)
			(end 0.7874 0.4064)
			(stroke
				(width 0.1524)
				(type default)
			)
			(layer "B.SilkS")
		)
		(fp_line
			(start 0.7874 -0.4064)
			(end -0.7874 -0.4064)
			(stroke
				(width 0.1524)
				(type default)
			)
			(layer "B.SilkS")
		)
		(fp_line
			(start 0.7874 0.4064)
			(end 0.7874 -0.4064)
			(stroke
				(width 0.1524)
				(type default)
			)
			(layer "B.SilkS")
		)
		(fp_line
			(start -0.67945 -0.3048)
			(end -0.67945 0.3048)
			(stroke
				(width 0.1)
				(type default)
			)
			(layer "B.Fab")
		)
		(fp_line
			(start -0.67945 0.3048)
			(end -0.120396 0.3048)
			(stroke
				(width 0.1)
				(type default)
			)
			(layer "B.Fab")
		)
		(fp_line
			(start -0.12065 -0.3048)
			(end -0.67945 -0.3048)
			(stroke
				(width 0.1)
				(type default)
			)
			(layer "B.Fab")
		)
		(fp_line
			(start -0.12065 -0.2794)
			(end -0.12065 -0.3048)
			(stroke
				(width 0.1)
				(type default)
			)
			(layer "B.Fab")
		)
		(fp_line
			(start -0.120396 0.2794)
			(end 0.12065 0.2794)
			(stroke
				(width 0.1)
				(type default)
			)
			(layer "B.Fab")
		)
		(fp_line
			(start -0.120396 0.3048)
			(end -0.120396 0.2794)
			(stroke
				(width 0.1)
				(type default)
			)
			(layer "B.Fab")
		)
		(fp_line
			(start 0.12065 -0.305054)
			(end 0.12065 -0.2794)
			(stroke
				(width 0.1)
				(type default)
			)
			(layer "B.Fab")
		)
		(fp_line
			(start 0.12065 -0.2794)
			(end -0.12065 -0.2794)
			(stroke
				(width 0.1)
				(type default)
			)
			(layer "B.Fab")
		)
		(fp_line
			(start 0.12065 0.2794)
			(end 0.12065 0.3048)
			(stroke
				(width 0.1)
				(type default)
			)
			(layer "B.Fab")
		)
		(fp_line
			(start 0.12065 0.3048)
			(end 0.67945 0.3048)
			(stroke
				(width 0.1)
				(type default)
			)
			(layer "B.Fab")
		)
		(fp_line
			(start 0.67945 -0.305054)
			(end 0.12065 -0.305054)
			(stroke
				(width 0.1)
				(type default)
			)
			(layer "B.Fab")
		)
		(fp_line
			(start 0.67945 0.3048)
			(end 0.67945 -0.305054)
			(stroke
				(width 0.1)
				(type default)
			)
			(layer "B.Fab")
		)
		(pad "1" smd circle
			(at 0.40005 0 180)
			(size 0 0)
			(layers "B.Cu" "B.Mask" "B.Paste")
			(net "P3V3_CLK_GEN_VDDXTAL_CK440_PEX")
		)
		(pad "2" smd circle
			(at -0.40005 0 180)
			(size 0 0)
			(layers "B.Cu" "B.Mask" "B.Paste")
			(net "GND")
		)
	)
	(footprint ""
		(layer "B.Cu")
		(at 222.482664 -204.44206 -90)
		(property "Reference" "R5527"
			(at 0 0 90)
			(layer "B.SilkS")
			(hide yes)
			(effects
				(font
					(size 1.27 1.27)
				)
				(justify mirror)
			)
		)
		(property "Value" ""
			(at 0 0 90)
			(layer "B.Fab")
			(effects
				(font
					(size 1.27 1.27)
				)
				(justify mirror)
			)
		)
		(duplicate_pad_numbers_are_jumpers no)
		(fp_line
			(start -0.7874 0.4064)
			(end 0.7874 0.4064)
			(stroke
				(width 0.1524)
				(type default)
			)
			(layer "B.SilkS")
		)
		(fp_line
			(start 0.7874 0.4064)
			(end 0.7874 -0.4064)
			(stroke
				(width 0.1524)
				(type default)
			)
			(layer "B.SilkS")
		)
		(fp_line
			(start -0.7874 -0.4064)
			(end -0.7874 0.4064)
			(stroke
				(width 0.1524)
				(type default)
			)
			(layer "B.SilkS")
		)
		(fp_line
			(start 0.7874 -0.4064)
			(end -0.7874 -0.4064)
			(stroke
				(width 0.1524)
				(type default)
			)
			(layer "B.SilkS")
		)
		(fp_line
			(start -0.67945 0.3048)
			(end -0.120396 0.3048)
			(stroke
				(width 0.1)
				(type default)
			)
			(layer "B.Fab")
		)
		(fp_line
			(start -0.120396 0.3048)
			(end -0.120396 0.2794)
			(stroke
				(width 0.1)
				(type default)
			)
			(layer "B.Fab")
		)
		(fp_line
			(start 0.12065 0.3048)
			(end 0.67945 0.3048)
			(stroke
				(width 0.1)
				(type default)
			)
			(layer "B.Fab")
		)
		(fp_line
			(start 0.67945 0.3048)
			(end 0.67945 -0.305054)
			(stroke
				(width 0.1)
				(type default)
			)
			(layer "B.Fab")
		)
		(fp_line
			(start -0.120396 0.2794)
			(end 0.12065 0.2794)
			(stroke
				(width 0.1)
				(type default)
			)
			(layer "B.Fab")
		)
		(fp_line
			(start 0.12065 0.2794)
			(end 0.12065 0.3048)
			(stroke
				(width 0.1)
				(type default)
			)
			(layer "B.Fab")
		)
		(fp_line
			(start -0.12065 -0.2794)
			(end -0.12065 -0.3048)
			(stroke
				(width 0.1)
				(type default)
			)
			(layer "B.Fab")
		)
		(fp_line
			(start 0.12065 -0.2794)
			(end -0.12065 -0.2794)
			(stroke
				(width 0.1)
				(type default)
			)
			(layer "B.Fab")
		)
		(fp_line
			(start -0.67945 -0.3048)
			(end -0.67945 0.3048)
			(stroke
				(width 0.1)
				(type default)
			)
			(layer "B.Fab")
		)
		(fp_line
			(start -0.12065 -0.3048)
			(end -0.67945 -0.3048)
			(stroke
				(width 0.1)
				(type default)
			)
			(layer "B.Fab")
		)
		(fp_line
			(start 0.12065 -0.305054)
			(end 0.12065 -0.2794)
			(stroke
				(width 0.1)
				(type default)
			)
			(layer "B.Fab")
		)
		(fp_line
			(start 0.67945 -0.305054)
			(end 0.12065 -0.305054)
			(stroke
				(width 0.1)
				(type default)
			)
			(layer "B.Fab")
		)
		(pad "1" smd circle
			(at 0.40005 0 90)
			(size 0 0)
			(layers "B.Cu" "B.Mask" "B.Paste")
			(net "P3V3_AUX")
		)
		(pad "2" smd circle
			(at -0.40005 0 90)
			(size 0 0)
			(layers "B.Cu" "B.Mask" "B.Paste")
			(net "SGPIO_BIC_DOUT")
		)
	)
	(footprint ""
		(layer "B.Cu")
		(at 217.235786 -212.206586 180)
		(property "Reference" "R5722"
			(at 0 0 0)
			(layer "B.SilkS")
			(hide yes)
			(effects
				(font
					(size 1.27 1.27)
				)
				(justify mirror)
			)
		)
		(property "Value" ""
			(at 0 0 0)
			(layer "B.Fab")
			(effects
				(font
					(size 1.27 1.27)
				)
				(justify mirror)
			)
		)
		(duplicate_pad_numbers_are_jumpers no)
		(fp_line
			(start 0.7874 0.4064)
			(end 0.7874 -0.4064)
			(stroke
				(width 0.1524)
				(type default)
			)
			(layer "B.SilkS")
		)
		(fp_line
			(start 0.7874 -0.4064)
			(end -0.7874 -0.4064)
			(stroke
				(width 0.1524)
				(type default)
			)
			(layer "B.SilkS")
		)
		(fp_line
			(start -0.7874 0.4064)
			(end 0.7874 0.4064)
			(stroke
				(width 0.1524)
				(type default)
			)
			(layer "B.SilkS")
		)
		(fp_line
			(start -0.7874 -0.4064)
			(end -0.7874 0.4064)
			(stroke
				(width 0.1524)
				(type default)
			)
			(layer "B.SilkS")
		)
		(fp_line
			(start 0.67945 0.3048)
			(end 0.67945 -0.305054)
			(stroke
				(width 0.1)
				(type default)
			)
			(layer "B.Fab")
		)
		(fp_line
			(start 0.67945 -0.305054)
			(end 0.12065 -0.305054)
			(stroke
				(width 0.1)
				(type default)
			)
			(layer "B.Fab")
		)
		(fp_line
			(start 0.12065 0.3048)
			(end 0.67945 0.3048)
			(stroke
				(width 0.1)
				(type default)
			)
			(layer "B.Fab")
		)
		(fp_line
			(start 0.12065 0.2794)
			(end 0.12065 0.3048)
			(stroke
				(width 0.1)
				(type default)
			)
			(layer "B.Fab")
		)
		(fp_line
			(start 0.12065 -0.2794)
			(end -0.12065 -0.2794)
			(stroke
				(width 0.1)
				(type default)
			)
			(layer "B.Fab")
		)
		(fp_line
			(start 0.12065 -0.305054)
			(end 0.12065 -0.2794)
			(stroke
				(width 0.1)
				(type default)
			)
			(layer "B.Fab")
		)
		(fp_line
			(start -0.120396 0.3048)
			(end -0.120396 0.2794)
			(stroke
				(width 0.1)
				(type default)
			)
			(layer "B.Fab")
		)
		(fp_line
			(start -0.120396 0.2794)
			(end 0.12065 0.2794)
			(stroke
				(width 0.1)
				(type default)
			)
			(layer "B.Fab")
		)
		(fp_line
			(start -0.12065 -0.2794)
			(end -0.12065 -0.3048)
			(stroke
				(width 0.1)
				(type default)
			)
			(layer "B.Fab")
		)
		(fp_line
			(start -0.12065 -0.3048)
			(end -0.67945 -0.3048)
			(stroke
				(width 0.1)
				(type default)
			)
			(layer "B.Fab")
		)
		(fp_line
			(start -0.67945 0.3048)
			(end -0.120396 0.3048)
			(stroke
				(width 0.1)
				(type default)
			)
			(layer "B.Fab")
		)
		(fp_line
			(start -0.67945 -0.3048)
			(end -0.67945 0.3048)
			(stroke
				(width 0.1)
				(type default)
			)
			(layer "B.Fab")
		)
		(pad "1" smd circle
			(at 0.40005 0)
			(size 0 0)
			(layers "B.Cu" "B.Mask" "B.Paste")
			(net "RST_PEX_USB_HUB_R_N")
		)
		(pad "2" smd circle
			(at -0.40005 0)
			(size 0 0)
			(layers "B.Cu" "B.Mask" "B.Paste")
			(net "RST_PEX_USB_HUB_N")
		)
	)
	(footprint ""
		(layer "B.Cu")
		(at 173.850046 -288.299906 90)
		(property "Reference" "C3093"
			(at 0 0 90)
			(layer "B.SilkS")
			(hide yes)
			(effects
				(font
					(size 1.27 1.27)
				)
				(justify mirror)
			)
		)
		(property "Value" ""
			(at 0 0 90)
			(layer "B.Fab")
			(effects
				(font
					(size 1.27 1.27)
				)
				(justify mirror)
			)
		)
		(duplicate_pad_numbers_are_jumpers no)
		(fp_line
			(start 0.299974 -0.150114)
			(end -0.299974 -0.150114)
			(stroke
				(width 0.1)
				(type default)
			)
			(layer "B.Fab")
		)
		(fp_line
			(start -0.299974 -0.150114)
			(end -0.299974 0.150114)
			(stroke
				(width 0.1)
				(type default)
			)
			(layer "B.Fab")
		)
		(fp_line
			(start 0.299974 0.150114)
			(end 0.299974 -0.150114)
			(stroke
				(width 0.1)
				(type default)
			)
			(layer "B.Fab")
		)
		(fp_line
			(start -0.299974 0.150114)
			(end 0.299974 0.150114)
			(stroke
				(width 0.1)
				(type default)
			)
			(layer "B.Fab")
		)
		(pad "1" smd rect
			(at 0.2667 0 270)
			(size 0.3048 0.381)
			(layers "B.Cu" "B.Mask" "B.Paste")
			(net "P1V25_PEX1")
		)
		(pad "2" smd rect
			(at -0.2667 0 270)
			(size 0.3048 0.381)
			(layers "B.Cu" "B.Mask" "B.Paste")
			(net "GND")
		)
	)
	(footprint ""
		(layer "B.Cu")
		(at 243.568982 -234.471464)
		(property "Reference" "R6815"
			(at 0 0 0)
			(layer "B.SilkS")
			(hide yes)
			(effects
				(font
					(size 1.27 1.27)
				)
				(justify mirror)
			)
		)
		(property "Value" ""
			(at 0 0 0)
			(layer "B.Fab")
			(effects
				(font
					(size 1.27 1.27)
				)
				(justify mirror)
			)
		)
		(duplicate_pad_numbers_are_jumpers no)
		(fp_line
			(start -0.7874 -0.4064)
			(end -0.7874 0.4064)
			(stroke
				(width 0.1524)
				(type default)
			)
			(layer "B.SilkS")
		)
		(fp_line
			(start -0.7874 0.4064)
			(end 0.7874 0.4064)
			(stroke
				(width 0.1524)
				(type default)
			)
			(layer "B.SilkS")
		)
		(fp_line
			(start 0.7874 -0.4064)
			(end -0.7874 -0.4064)
			(stroke
				(width 0.1524)
				(type default)
			)
			(layer "B.SilkS")
		)
		(fp_line
			(start 0.7874 0.4064)
			(end 0.7874 -0.4064)
			(stroke
				(width 0.1524)
				(type default)
			)
			(layer "B.SilkS")
		)
		(fp_line
			(start -0.67945 -0.3048)
			(end -0.67945 0.3048)
			(stroke
				(width 0.1)
				(type default)
			)
			(layer "B.Fab")
		)
		(fp_line
			(start -0.67945 0.3048)
			(end -0.120396 0.3048)
			(stroke
				(width 0.1)
				(type default)
			)
			(layer "B.Fab")
		)
		(fp_line
			(start -0.12065 -0.3048)
			(end -0.67945 -0.3048)
			(stroke
				(width 0.1)
				(type default)
			)
			(layer "B.Fab")
		)
		(fp_line
			(start -0.12065 -0.2794)
			(end -0.12065 -0.3048)
			(stroke
				(width 0.1)
				(type default)
			)
			(layer "B.Fab")
		)
		(fp_line
			(start -0.120396 0.2794)
			(end 0.12065 0.2794)
			(stroke
				(width 0.1)
				(type default)
			)
			(layer "B.Fab")
		)
		(fp_line
			(start -0.120396 0.3048)
			(end -0.120396 0.2794)
			(stroke
				(width 0.1)
				(type default)
			)
			(layer "B.Fab")
		)
		(fp_line
			(start 0.12065 -0.305054)
			(end 0.12065 -0.2794)
			(stroke
				(width 0.1)
				(type default)
			)
			(layer "B.Fab")
		)
		(fp_line
			(start 0.12065 -0.2794)
			(end -0.12065 -0.2794)
			(stroke
				(width 0.1)
				(type default)
			)
			(layer "B.Fab")
		)
		(fp_line
			(start 0.12065 0.2794)
			(end 0.12065 0.3048)
			(stroke
				(width 0.1)
				(type default)
			)
			(layer "B.Fab")
		)
		(fp_line
			(start 0.12065 0.3048)
			(end 0.67945 0.3048)
			(stroke
				(width 0.1)
				(type default)
			)
			(layer "B.Fab")
		)
		(fp_line
			(start 0.67945 -0.305054)
			(end 0.12065 -0.305054)
			(stroke
				(width 0.1)
				(type default)
			)
			(layer "B.Fab")
		)
		(fp_line
			(start 0.67945 0.3048)
			(end 0.67945 -0.305054)
			(stroke
				(width 0.1)
				(type default)
			)
			(layer "B.Fab")
		)
		(pad "1" smd circle
			(at 0.40005 0 180)
			(size 0 0)
			(layers "B.Cu" "B.Mask" "B.Paste")
			(net "BOARD_TYPE_2_ADC_R")
		)
		(pad "2" smd circle
			(at -0.40005 0 180)
			(size 0 0)
			(layers "B.Cu" "B.Mask" "B.Paste")
			(net "P3V3_AUX")
		)
	)
	(footprint ""
		(layer "B.Cu")
		(at 181.92496 -293.99992 -90)
		(property "Reference" "C1386"
			(at 0 0 90)
			(layer "B.SilkS")
			(hide yes)
			(effects
				(font
					(size 1.27 1.27)
				)
				(justify mirror)
			)
		)
		(property "Value" ""
			(at 0 0 90)
			(layer "B.Fab")
			(effects
				(font
					(size 1.27 1.27)
				)
				(justify mirror)
			)
		)
		(duplicate_pad_numbers_are_jumpers no)
		(fp_line
			(start -0.299974 0.150114)
			(end 0.299974 0.150114)
			(stroke
				(width 0.1)
				(type default)
			)
			(layer "B.Fab")
		)
		(fp_line
			(start 0.299974 0.150114)
			(end 0.299974 -0.150114)
			(stroke
				(width 0.1)
				(type default)
			)
			(layer "B.Fab")
		)
		(fp_line
			(start -0.299974 -0.150114)
			(end -0.299974 0.150114)
			(stroke
				(width 0.1)
				(type default)
			)
			(layer "B.Fab")
		)
		(fp_line
			(start 0.299974 -0.150114)
			(end -0.299974 -0.150114)
			(stroke
				(width 0.1)
				(type default)
			)
			(layer "B.Fab")
		)
		(pad "1" smd rect
			(at 0.2667 0 90)
			(size 0.3048 0.381)
			(layers "B.Cu" "B.Mask" "B.Paste")
			(net "P0V8_PEX1")
		)
		(pad "2" smd rect
			(at -0.2667 0 90)
			(size 0.3048 0.381)
			(layers "B.Cu" "B.Mask" "B.Paste")
			(net "GND")
		)
	)
	(footprint ""
		(layer "B.Cu")
		(at 285.199836 -292.099746 90)
		(property "Reference" "C1700"
			(at 0 0 90)
			(layer "B.SilkS")
			(hide yes)
			(effects
				(font
					(size 1.27 1.27)
				)
				(justify mirror)
			)
		)
		(property "Value" ""
			(at 0 0 90)
			(layer "B.Fab")
			(effects
				(font
					(size 1.27 1.27)
				)
				(justify mirror)
			)
		)
		(duplicate_pad_numbers_are_jumpers no)
		(fp_line
			(start 0.299974 -0.150114)
			(end -0.299974 -0.150114)
			(stroke
				(width 0.1)
				(type default)
			)
			(layer "B.Fab")
		)
		(fp_line
			(start -0.299974 -0.150114)
			(end -0.299974 0.150114)
			(stroke
				(width 0.1)
				(type default)
			)
			(layer "B.Fab")
		)
		(fp_line
			(start 0.299974 0.150114)
			(end 0.299974 -0.150114)
			(stroke
				(width 0.1)
				(type default)
			)
			(layer "B.Fab")
		)
		(fp_line
			(start -0.299974 0.150114)
			(end 0.299974 0.150114)
			(stroke
				(width 0.1)
				(type default)
			)
			(layer "B.Fab")
		)
		(pad "1" smd rect
			(at 0.2667 0 270)
			(size 0.3048 0.381)
			(layers "B.Cu" "B.Mask" "B.Paste")
			(net "P0V8_SERDES_VDDA_PEX2")
		)
		(pad "2" smd rect
			(at -0.2667 0 270)
			(size 0.3048 0.381)
			(layers "B.Cu" "B.Mask" "B.Paste")
			(net "GND")
		)
	)
	(footprint ""
		(layer "B.Cu")
		(at 217.24366 -225.477578)
		(property "Reference" "R1492"
			(at 0 0 0)
			(layer "B.SilkS")
			(hide yes)
			(effects
				(font
					(size 1.27 1.27)
				)
				(justify mirror)
			)
		)
		(property "Value" ""
			(at 0 0 0)
			(layer "B.Fab")
			(effects
				(font
					(size 1.27 1.27)
				)
				(justify mirror)
			)
		)
		(duplicate_pad_numbers_are_jumpers no)
		(fp_line
			(start -0.7874 -0.4064)
			(end -0.7874 0.4064)
			(stroke
				(width 0.1524)
				(type default)
			)
			(layer "B.SilkS")
		)
		(fp_line
			(start -0.7874 0.4064)
			(end 0.7874 0.4064)
			(stroke
				(width 0.1524)
				(type default)
			)
			(layer "B.SilkS")
		)
		(fp_line
			(start 0.7874 -0.4064)
			(end -0.7874 -0.4064)
			(stroke
				(width 0.1524)
				(type default)
			)
			(layer "B.SilkS")
		)
		(fp_line
			(start 0.7874 0.4064)
			(end 0.7874 -0.4064)
			(stroke
				(width 0.1524)
				(type default)
			)
			(layer "B.SilkS")
		)
		(fp_line
			(start -0.67945 -0.3048)
			(end -0.67945 0.3048)
			(stroke
				(width 0.1)
				(type default)
			)
			(layer "B.Fab")
		)
		(fp_line
			(start -0.67945 0.3048)
			(end -0.120396 0.3048)
			(stroke
				(width 0.1)
				(type default)
			)
			(layer "B.Fab")
		)
		(fp_line
			(start -0.12065 -0.3048)
			(end -0.67945 -0.3048)
			(stroke
				(width 0.1)
				(type default)
			)
			(layer "B.Fab")
		)
		(fp_line
			(start -0.12065 -0.2794)
			(end -0.12065 -0.3048)
			(stroke
				(width 0.1)
				(type default)
			)
			(layer "B.Fab")
		)
		(fp_line
			(start -0.120396 0.2794)
			(end 0.12065 0.2794)
			(stroke
				(width 0.1)
				(type default)
			)
			(layer "B.Fab")
		)
		(fp_line
			(start -0.120396 0.3048)
			(end -0.120396 0.2794)
			(stroke
				(width 0.1)
				(type default)
			)
			(layer "B.Fab")
		)
		(fp_line
			(start 0.12065 -0.305054)
			(end 0.12065 -0.2794)
			(stroke
				(width 0.1)
				(type default)
			)
			(layer "B.Fab")
		)
		(fp_line
			(start 0.12065 -0.2794)
			(end -0.12065 -0.2794)
			(stroke
				(width 0.1)
				(type default)
			)
			(layer "B.Fab")
		)
		(fp_line
			(start 0.12065 0.2794)
			(end 0.12065 0.3048)
			(stroke
				(width 0.1)
				(type default)
			)
			(layer "B.Fab")
		)
		(fp_line
			(start 0.12065 0.3048)
			(end 0.67945 0.3048)
			(stroke
				(width 0.1)
				(type default)
			)
			(layer "B.Fab")
		)
		(fp_line
			(start 0.67945 -0.305054)
			(end 0.12065 -0.305054)
			(stroke
				(width 0.1)
				(type default)
			)
			(layer "B.Fab")
		)
		(fp_line
			(start 0.67945 0.3048)
			(end 0.67945 -0.305054)
			(stroke
				(width 0.1)
				(type default)
			)
			(layer "B.Fab")
		)
		(pad "1" smd circle
			(at 0.40005 0 180)
			(size 0 0)
			(layers "B.Cu" "B.Mask" "B.Paste")
			(net "SMB_FIO_SDA")
		)
		(pad "2" smd circle
			(at -0.40005 0 180)
			(size 0 0)
			(layers "B.Cu" "B.Mask" "B.Paste")
			(net "SMB_FIO_R1_SDA")
		)
	)
)
